(kicad_pcb
	(version 20260206)
	(generator "pcbnew")
	(generator_version "10.0")
	(general
		(thickness 1.6)
		(legacy_teardrops no)
	)
	(paper "A4")
	(title_block
		(title "03242023_DA0F0TMBIJ0_F0T_Motherboard_J_brd_V01_OCP.brd")
		(comment 1 "Grand Teton / footprints 3014-3019 of 6105")
	)
	(layers
		(0 "F.Cu" signal "TOP")
		(4 "In1.Cu" signal "GND")
		(6 "In2.Cu" signal "IN1")
		(8 "In3.Cu" signal "GND1")
		(10 "In4.Cu" signal "IN2")
		(12 "In5.Cu" signal "GND2")
		(14 "In6.Cu" signal "IN3")
		(16 "In7.Cu" signal "GND3")
		(18 "In8.Cu" signal "VCC")
		(20 "In9.Cu" signal "VCC1")
		(22 "In10.Cu" signal "GND4")
		(24 "In11.Cu" signal "IN4")
		(26 "In12.Cu" signal "GND5")
		(28 "In13.Cu" signal "IN5")
		(30 "In14.Cu" signal "GND6")
		(32 "In15.Cu" signal "IN6")
		(34 "In16.Cu" signal "GND7")
		(2 "B.Cu" signal "BOTTOM")
		(9 "F.Adhes" user "F.Adhesive")
		(11 "B.Adhes" user "B.Adhesive")
		(13 "F.Paste" user "Package Geometry/Pastemask Top")
		(15 "B.Paste" user "Package Geometry/Pastemask Bottom")
		(5 "F.SilkS" user "Ref Des/Silkscreen Top")
		(7 "B.SilkS" user "Ref Des/Silkscreen Bottom")
		(1 "F.Mask" user "Board Geometry/Soldermask Top")
		(3 "B.Mask" user "Board Geometry/Soldermask Bottom")
		(17 "Dwgs.User" user "User.Drawings")
		(19 "Cmts.User" user "User.Comments")
		(21 "Eco1.User" user "User.Eco1")
		(23 "Eco2.User" user "User.Eco2")
		(25 "Edge.Cuts" user "Board Geometry/Outline")
		(27 "Margin" user)
		(31 "F.CrtYd" user "Package Geometry/Place Bound Top")
		(29 "B.CrtYd" user "Package Geometry/Place Bound Bottom")
		(35 "F.Fab" user "Ref Des/Assembly Top")
		(33 "B.Fab" user "Ref Des/Assembly Bottom")
	)
	(footprint ""
		(layer "F.Cu")
		(at 204.99578 -113.0554 180)
		(property "Reference" "R4723"
			(at 0 0 180)
			(layer "F.SilkS")
			(hide yes)
			(effects
				(font
					(size 1.27 1.27)
				)
			)
		)
		(property "Value" ""
			(at 0 0 180)
			(layer "F.Fab")
			(effects
				(font
					(size 1.27 1.27)
				)
			)
		)
		(duplicate_pad_numbers_are_jumpers no)
		(fp_line
			(start 0.7874 0.4064)
			(end -0.7874 0.4064)
			(stroke
				(width 0.1524)
				(type default)
			)
			(layer "F.SilkS")
		)
		(fp_line
			(start 0.7874 -0.4064)
			(end 0.7874 0.4064)
			(stroke
				(width 0.1524)
				(type default)
			)
			(layer "F.SilkS")
		)
		(fp_line
			(start -0.7874 0.4064)
			(end -0.7874 -0.4064)
			(stroke
				(width 0.1524)
				(type default)
			)
			(layer "F.SilkS")
		)
		(fp_line
			(start -0.7874 -0.4064)
			(end 0.7874 -0.4064)
			(stroke
				(width 0.1524)
				(type default)
			)
			(layer "F.SilkS")
		)
		(fp_line
			(start 0.67945 0.3048)
			(end 0.120396 0.3048)
			(stroke
				(width 0.1)
				(type default)
			)
			(layer "F.Fab")
		)
		(fp_line
			(start 0.67945 -0.3048)
			(end 0.67945 0.3048)
			(stroke
				(width 0.1)
				(type default)
			)
			(layer "F.Fab")
		)
		(fp_line
			(start 0.12065 -0.2794)
			(end 0.12065 -0.3048)
			(stroke
				(width 0.1)
				(type default)
			)
			(layer "F.Fab")
		)
		(fp_line
			(start 0.12065 -0.3048)
			(end 0.67945 -0.3048)
			(stroke
				(width 0.1)
				(type default)
			)
			(layer "F.Fab")
		)
		(fp_line
			(start 0.120396 0.3048)
			(end 0.120396 0.2794)
			(stroke
				(width 0.1)
				(type default)
			)
			(layer "F.Fab")
		)
		(fp_line
			(start 0.120396 0.2794)
			(end -0.12065 0.2794)
			(stroke
				(width 0.1)
				(type default)
			)
			(layer "F.Fab")
		)
		(fp_line
			(start -0.12065 0.3048)
			(end -0.67945 0.3048)
			(stroke
				(width 0.1)
				(type default)
			)
			(layer "F.Fab")
		)
		(fp_line
			(start -0.12065 0.2794)
			(end -0.12065 0.3048)
			(stroke
				(width 0.1)
				(type default)
			)
			(layer "F.Fab")
		)
		(fp_line
			(start -0.12065 -0.2794)
			(end 0.12065 -0.2794)
			(stroke
				(width 0.1)
				(type default)
			)
			(layer "F.Fab")
		)
		(fp_line
			(start -0.12065 -0.305054)
			(end -0.12065 -0.2794)
			(stroke
				(width 0.1)
				(type default)
			)
			(layer "F.Fab")
		)
		(fp_line
			(start -0.67945 0.3048)
			(end -0.67945 -0.305054)
			(stroke
				(width 0.1)
				(type default)
			)
			(layer "F.Fab")
		)
		(fp_line
			(start -0.67945 -0.305054)
			(end -0.12065 -0.305054)
			(stroke
				(width 0.1)
				(type default)
			)
			(layer "F.Fab")
		)
		(pad "1" smd circle
			(at -0.40005 0 180)
			(size 0 0)
			(layers "F.Cu" "F.Mask" "F.Paste")
			(net "FM_PCH_BMC_RST_R_N")
		)
		(pad "2" smd circle
			(at 0.40005 0 180)
			(size 0 0)
			(layers "F.Cu" "F.Mask" "F.Paste")
			(net "FM_PCH_BMC_RST_N")
		)
	)
	(footprint ""
		(layer "F.Cu")
		(at 166.34333 -131.976876 -90)
		(property "Reference" "R1607"
			(at 0 0 270)
			(layer "F.SilkS")
			(hide yes)
			(effects
				(font
					(size 1.27 1.27)
				)
			)
		)
		(property "Value" ""
			(at 0 0 270)
			(layer "F.Fab")
			(effects
				(font
					(size 1.27 1.27)
				)
			)
		)
		(duplicate_pad_numbers_are_jumpers no)
		(fp_line
			(start -0.7874 0.4064)
			(end -0.7874 -0.4064)
			(stroke
				(width 0.1524)
				(type default)
			)
			(layer "F.SilkS")
		)
		(fp_line
			(start 0.7874 0.4064)
			(end -0.7874 0.4064)
			(stroke
				(width 0.1524)
				(type default)
			)
			(layer "F.SilkS")
		)
		(fp_line
			(start -0.7874 -0.4064)
			(end 0.7874 -0.4064)
			(stroke
				(width 0.1524)
				(type default)
			)
			(layer "F.SilkS")
		)
		(fp_line
			(start 0.7874 -0.4064)
			(end 0.7874 0.4064)
			(stroke
				(width 0.1524)
				(type default)
			)
			(layer "F.SilkS")
		)
		(fp_line
			(start -0.67945 0.3048)
			(end -0.67945 -0.305054)
			(stroke
				(width 0.1)
				(type default)
			)
			(layer "F.Fab")
		)
		(fp_line
			(start -0.12065 0.3048)
			(end -0.67945 0.3048)
			(stroke
				(width 0.1)
				(type default)
			)
			(layer "F.Fab")
		)
		(fp_line
			(start 0.120396 0.3048)
			(end 0.120396 0.2794)
			(stroke
				(width 0.1)
				(type default)
			)
			(layer "F.Fab")
		)
		(fp_line
			(start 0.67945 0.3048)
			(end 0.120396 0.3048)
			(stroke
				(width 0.1)
				(type default)
			)
			(layer "F.Fab")
		)
		(fp_line
			(start -0.12065 0.2794)
			(end -0.12065 0.3048)
			(stroke
				(width 0.1)
				(type default)
			)
			(layer "F.Fab")
		)
		(fp_line
			(start 0.120396 0.2794)
			(end -0.12065 0.2794)
			(stroke
				(width 0.1)
				(type default)
			)
			(layer "F.Fab")
		)
		(fp_line
			(start -0.12065 -0.2794)
			(end 0.12065 -0.2794)
			(stroke
				(width 0.1)
				(type default)
			)
			(layer "F.Fab")
		)
		(fp_line
			(start 0.12065 -0.2794)
			(end 0.12065 -0.3048)
			(stroke
				(width 0.1)
				(type default)
			)
			(layer "F.Fab")
		)
		(fp_line
			(start 0.12065 -0.3048)
			(end 0.67945 -0.3048)
			(stroke
				(width 0.1)
				(type default)
			)
			(layer "F.Fab")
		)
		(fp_line
			(start 0.67945 -0.3048)
			(end 0.67945 0.3048)
			(stroke
				(width 0.1)
				(type default)
			)
			(layer "F.Fab")
		)
		(fp_line
			(start -0.67945 -0.305054)
			(end -0.12065 -0.305054)
			(stroke
				(width 0.1)
				(type default)
			)
			(layer "F.Fab")
		)
		(fp_line
			(start -0.12065 -0.305054)
			(end -0.12065 -0.2794)
			(stroke
				(width 0.1)
				(type default)
			)
			(layer "F.Fab")
		)
		(pad "1" smd circle
			(at -0.40005 0 270)
			(size 0 0)
			(layers "F.Cu" "F.Mask" "F.Paste")
			(net "FM_PS_EN_PLD_R")
		)
		(pad "2" smd circle
			(at 0.40005 0 270)
			(size 0 0)
			(layers "F.Cu" "F.Mask" "F.Paste")
			(net "VR_P5V_EN")
		)
	)
	(footprint ""
		(layer "F.Cu")
		(at 117.526816 -255.0541 90)
		(property "Reference" "C301"
			(at 0 0 90)
			(layer "F.SilkS")
			(hide yes)
			(effects
				(font
					(size 1.27 1.27)
				)
			)
		)
		(property "Value" ""
			(at 0 0 90)
			(layer "F.Fab")
			(effects
				(font
					(size 1.27 1.27)
				)
			)
		)
		(duplicate_pad_numbers_are_jumpers no)
		(fp_line
			(start 0.7874 -0.4064)
			(end 0.7874 0.4064)
			(stroke
				(width 0.1524)
				(type default)
			)
			(layer "F.SilkS")
		)
		(fp_line
			(start -0.7874 -0.4064)
			(end 0.7874 -0.4064)
			(stroke
				(width 0.1524)
				(type default)
			)
			(layer "F.SilkS")
		)
		(fp_line
			(start 0.7874 0.4064)
			(end -0.7874 0.4064)
			(stroke
				(width 0.1524)
				(type default)
			)
			(layer "F.SilkS")
		)
		(fp_line
			(start -0.7874 0.4064)
			(end -0.7874 -0.4064)
			(stroke
				(width 0.1524)
				(type default)
			)
			(layer "F.SilkS")
		)
		(fp_line
			(start -0.12065 -0.305054)
			(end -0.12065 -0.2794)
			(stroke
				(width 0.1)
				(type default)
			)
			(layer "F.Fab")
		)
		(fp_line
			(start -0.67945 -0.305054)
			(end -0.12065 -0.305054)
			(stroke
				(width 0.1)
				(type default)
			)
			(layer "F.Fab")
		)
		(fp_line
			(start 0.67945 -0.3048)
			(end 0.67945 0.3048)
			(stroke
				(width 0.1)
				(type default)
			)
			(layer "F.Fab")
		)
		(fp_line
			(start 0.12065 -0.3048)
			(end 0.67945 -0.3048)
			(stroke
				(width 0.1)
				(type default)
			)
			(layer "F.Fab")
		)
		(fp_line
			(start 0.12065 -0.2794)
			(end 0.12065 -0.3048)
			(stroke
				(width 0.1)
				(type default)
			)
			(layer "F.Fab")
		)
		(fp_line
			(start -0.12065 -0.2794)
			(end 0.12065 -0.2794)
			(stroke
				(width 0.1)
				(type default)
			)
			(layer "F.Fab")
		)
		(fp_line
			(start 0.120396 0.2794)
			(end -0.12065 0.2794)
			(stroke
				(width 0.1)
				(type default)
			)
			(layer "F.Fab")
		)
		(fp_line
			(start -0.12065 0.2794)
			(end -0.12065 0.3048)
			(stroke
				(width 0.1)
				(type default)
			)
			(layer "F.Fab")
		)
		(fp_line
			(start 0.67945 0.3048)
			(end 0.120396 0.3048)
			(stroke
				(width 0.1)
				(type default)
			)
			(layer "F.Fab")
		)
		(fp_line
			(start 0.120396 0.3048)
			(end 0.120396 0.2794)
			(stroke
				(width 0.1)
				(type default)
			)
			(layer "F.Fab")
		)
		(fp_line
			(start -0.12065 0.3048)
			(end -0.67945 0.3048)
			(stroke
				(width 0.1)
				(type default)
			)
			(layer "F.Fab")
		)
		(fp_line
			(start -0.67945 0.3048)
			(end -0.67945 -0.305054)
			(stroke
				(width 0.1)
				(type default)
			)
			(layer "F.Fab")
		)
		(pad "1" smd circle
			(at -0.40005 0 90)
			(size 0 0)
			(layers "F.Cu" "F.Mask" "F.Paste")
			(net "PVCCIN_CPU1")
		)
		(pad "2" smd circle
			(at 0.40005 0 90)
			(size 0 0)
			(layers "F.Cu" "F.Mask" "F.Paste")
			(net "GND")
		)
	)
	(footprint ""
		(layer "F.Cu")
		(at 331.224636 -17.414748 180)
		(property "Reference" "R2451"
			(at 0 0 180)
			(layer "F.SilkS")
			(hide yes)
			(effects
				(font
					(size 1.27 1.27)
				)
			)
		)
		(property "Value" ""
			(at 0 0 180)
			(layer "F.Fab")
			(effects
				(font
					(size 1.27 1.27)
				)
			)
		)
		(duplicate_pad_numbers_are_jumpers no)
		(fp_line
			(start 0.7874 0.4064)
			(end -0.7874 0.4064)
			(stroke
				(width 0.1524)
				(type default)
			)
			(layer "F.SilkS")
		)
		(fp_line
			(start 0.7874 -0.4064)
			(end 0.7874 0.4064)
			(stroke
				(width 0.1524)
				(type default)
			)
			(layer "F.SilkS")
		)
		(fp_line
			(start -0.7874 0.4064)
			(end -0.7874 -0.4064)
			(stroke
				(width 0.1524)
				(type default)
			)
			(layer "F.SilkS")
		)
		(fp_line
			(start -0.7874 -0.4064)
			(end 0.7874 -0.4064)
			(stroke
				(width 0.1524)
				(type default)
			)
			(layer "F.SilkS")
		)
		(fp_line
			(start 0.67945 0.3048)
			(end 0.120396 0.3048)
			(stroke
				(width 0.1)
				(type default)
			)
			(layer "F.Fab")
		)
		(fp_line
			(start 0.67945 -0.3048)
			(end 0.67945 0.3048)
			(stroke
				(width 0.1)
				(type default)
			)
			(layer "F.Fab")
		)
		(fp_line
			(start 0.12065 -0.2794)
			(end 0.12065 -0.3048)
			(stroke
				(width 0.1)
				(type default)
			)
			(layer "F.Fab")
		)
		(fp_line
			(start 0.12065 -0.3048)
			(end 0.67945 -0.3048)
			(stroke
				(width 0.1)
				(type default)
			)
			(layer "F.Fab")
		)
		(fp_line
			(start 0.120396 0.3048)
			(end 0.120396 0.2794)
			(stroke
				(width 0.1)
				(type default)
			)
			(layer "F.Fab")
		)
		(fp_line
			(start 0.120396 0.2794)
			(end -0.12065 0.2794)
			(stroke
				(width 0.1)
				(type default)
			)
			(layer "F.Fab")
		)
		(fp_line
			(start -0.12065 0.3048)
			(end -0.67945 0.3048)
			(stroke
				(width 0.1)
				(type default)
			)
			(layer "F.Fab")
		)
		(fp_line
			(start -0.12065 0.2794)
			(end -0.12065 0.3048)
			(stroke
				(width 0.1)
				(type default)
			)
			(layer "F.Fab")
		)
		(fp_line
			(start -0.12065 -0.2794)
			(end 0.12065 -0.2794)
			(stroke
				(width 0.1)
				(type default)
			)
			(layer "F.Fab")
		)
		(fp_line
			(start -0.12065 -0.305054)
			(end -0.12065 -0.2794)
			(stroke
				(width 0.1)
				(type default)
			)
			(layer "F.Fab")
		)
		(fp_line
			(start -0.67945 0.3048)
			(end -0.67945 -0.305054)
			(stroke
				(width 0.1)
				(type default)
			)
			(layer "F.Fab")
		)
		(fp_line
			(start -0.67945 -0.305054)
			(end -0.12065 -0.305054)
			(stroke
				(width 0.1)
				(type default)
			)
			(layer "F.Fab")
		)
		(pad "1" smd circle
			(at -0.40005 0 180)
			(size 0 0)
			(layers "F.Cu" "F.Mask" "F.Paste")
			(net "P3V3_AUX")
		)
		(pad "2" smd circle
			(at 0.40005 0 180)
			(size 0 0)
			(layers "F.Cu" "F.Mask" "F.Paste")
			(net "FM_ESPI_PLD_R1_EN")
		)
	)
	(footprint ""
		(layer "F.Cu")
		(at 359.967276 -338.86013)
		(property "Reference" "PR145"
			(at 0 0 0)
			(layer "F.SilkS")
			(hide yes)
			(effects
				(font
					(size 1.27 1.27)
				)
			)
		)
		(property "Value" ""
			(at 0 0 0)
			(layer "F.Fab")
			(effects
				(font
					(size 1.27 1.27)
				)
			)
		)
		(duplicate_pad_numbers_are_jumpers no)
		(fp_line
			(start -0.7874 -0.4064)
			(end 0.7874 -0.4064)
			(stroke
				(width 0.1524)
				(type default)
			)
			(layer "F.SilkS")
		)
		(fp_line
			(start -0.7874 0.4064)
			(end -0.7874 -0.4064)
			(stroke
				(width 0.1524)
				(type default)
			)
			(layer "F.SilkS")
		)
		(fp_line
			(start 0.7874 -0.4064)
			(end 0.7874 0.4064)
			(stroke
				(width 0.1524)
				(type default)
			)
			(layer "F.SilkS")
		)
		(fp_line
			(start 0.7874 0.4064)
			(end -0.7874 0.4064)
			(stroke
				(width 0.1524)
				(type default)
			)
			(layer "F.SilkS")
		)
		(fp_line
			(start -0.67945 -0.305054)
			(end -0.12065 -0.305054)
			(stroke
				(width 0.1)
				(type default)
			)
			(layer "F.Fab")
		)
		(fp_line
			(start -0.67945 0.3048)
			(end -0.67945 -0.305054)
			(stroke
				(width 0.1)
				(type default)
			)
			(layer "F.Fab")
		)
		(fp_line
			(start -0.12065 -0.305054)
			(end -0.12065 -0.2794)
			(stroke
				(width 0.1)
				(type default)
			)
			(layer "F.Fab")
		)
		(fp_line
			(start -0.12065 -0.2794)
			(end 0.12065 -0.2794)
			(stroke
				(width 0.1)
				(type default)
			)
			(layer "F.Fab")
		)
		(fp_line
			(start -0.12065 0.2794)
			(end -0.12065 0.3048)
			(stroke
				(width 0.1)
				(type default)
			)
			(layer "F.Fab")
		)
		(fp_line
			(start -0.12065 0.3048)
			(end -0.67945 0.3048)
			(stroke
				(width 0.1)
				(type default)
			)
			(layer "F.Fab")
		)
		(fp_line
			(start 0.120396 0.2794)
			(end -0.12065 0.2794)
			(stroke
				(width 0.1)
				(type default)
			)
			(layer "F.Fab")
		)
		(fp_line
			(start 0.120396 0.3048)
			(end 0.120396 0.2794)
			(stroke
				(width 0.1)
				(type default)
			)
			(layer "F.Fab")
		)
		(fp_line
			(start 0.12065 -0.3048)
			(end 0.67945 -0.3048)
			(stroke
				(width 0.1)
				(type default)
			)
			(layer "F.Fab")
		)
		(fp_line
			(start 0.12065 -0.2794)
			(end 0.12065 -0.3048)
			(stroke
				(width 0.1)
				(type default)
			)
			(layer "F.Fab")
		)
		(fp_line
			(start 0.67945 -0.3048)
			(end 0.67945 0.3048)
			(stroke
				(width 0.1)
				(type default)
			)
			(layer "F.Fab")
		)
		(fp_line
			(start 0.67945 0.3048)
			(end 0.120396 0.3048)
			(stroke
				(width 0.1)
				(type default)
			)
			(layer "F.Fab")
		)
		(pad "1" smd circle
			(at -0.40005 0)
			(size 0 0)
			(layers "F.Cu" "F.Mask" "F.Paste")
			(net "PVCCIN_CPU0_LSET3")
		)
		(pad "2" smd circle
			(at 0.40005 0)
			(size 0 0)
			(layers "F.Cu" "F.Mask" "F.Paste")
			(net "GND")
		)
	)
	(footprint ""
		(layer "F.Cu")
		(at 371.796818 -417.17341 90)
		(property "Reference" "R4206"
			(at 0 0 90)
			(layer "F.SilkS")
			(hide yes)
			(effects
				(font
					(size 1.27 1.27)
				)
			)
		)
		(property "Value" ""
			(at 0 0 90)
			(layer "F.Fab")
			(effects
				(font
					(size 1.27 1.27)
				)
			)
		)
		(duplicate_pad_numbers_are_jumpers no)
		(fp_line
			(start 0.7874 -0.4064)
			(end 0.7874 0.4064)
			(stroke
				(width 0.1524)
				(type default)
			)
			(layer "F.SilkS")
		)
		(fp_line
			(start -0.7874 -0.4064)
			(end 0.7874 -0.4064)
			(stroke
				(width 0.1524)
				(type default)
			)
			(layer "F.SilkS")
		)
		(fp_line
			(start 0.7874 0.4064)
			(end -0.7874 0.4064)
			(stroke
				(width 0.1524)
				(type default)
			)
			(layer "F.SilkS")
		)
		(fp_line
			(start -0.7874 0.4064)
			(end -0.7874 -0.4064)
			(stroke
				(width 0.1524)
				(type default)
			)
			(layer "F.SilkS")
		)
		(fp_line
			(start -0.12065 -0.305054)
			(end -0.12065 -0.2794)
			(stroke
				(width 0.1)
				(type default)
			)
			(layer "F.Fab")
		)
		(fp_line
			(start -0.67945 -0.305054)
			(end -0.12065 -0.305054)
			(stroke
				(width 0.1)
				(type default)
			)
			(layer "F.Fab")
		)
		(fp_line
			(start 0.67945 -0.3048)
			(end 0.67945 0.3048)
			(stroke
				(width 0.1)
				(type default)
			)
			(layer "F.Fab")
		)
		(fp_line
			(start 0.12065 -0.3048)
			(end 0.67945 -0.3048)
			(stroke
				(width 0.1)
				(type default)
			)
			(layer "F.Fab")
		)
		(fp_line
			(start 0.12065 -0.2794)
			(end 0.12065 -0.3048)
			(stroke
				(width 0.1)
				(type default)
			)
			(layer "F.Fab")
		)
		(fp_line
			(start -0.12065 -0.2794)
			(end 0.12065 -0.2794)
			(stroke
				(width 0.1)
				(type default)
			)
			(layer "F.Fab")
		)
		(fp_line
			(start 0.120396 0.2794)
			(end -0.12065 0.2794)
			(stroke
				(width 0.1)
				(type default)
			)
			(layer "F.Fab")
		)
		(fp_line
			(start -0.12065 0.2794)
			(end -0.12065 0.3048)
			(stroke
				(width 0.1)
				(type default)
			)
			(layer "F.Fab")
		)
		(fp_line
			(start 0.67945 0.3048)
			(end 0.120396 0.3048)
			(stroke
				(width 0.1)
				(type default)
			)
			(layer "F.Fab")
		)
		(fp_line
			(start 0.120396 0.3048)
			(end 0.120396 0.2794)
			(stroke
				(width 0.1)
				(type default)
			)
			(layer "F.Fab")
		)
		(fp_line
			(start -0.12065 0.3048)
			(end -0.67945 0.3048)
			(stroke
				(width 0.1)
				(type default)
			)
			(layer "F.Fab")
		)
		(fp_line
			(start -0.67945 0.3048)
			(end -0.67945 -0.305054)
			(stroke
				(width 0.1)
				(type default)
			)
			(layer "F.Fab")
		)
		(pad "1" smd circle
			(at -0.40005 0 90)
			(size 0 0)
			(layers "F.Cu" "F.Mask" "F.Paste")
			(net "P3V3_AUX")
		)
		(pad "2" smd circle
			(at 0.40005 0 90)
			(size 0 0)
			(layers "F.Cu" "F.Mask" "F.Paste")
			(net "U270_0_ADD0")
		)
	)
)
